# T6G (Grand Teton) — schematic parts with pin connectivity, parts 8081–8081 of 8303; source: Cadence DE-HDL packaged netlist (pstxprt.dat, pstxnet.dat, pstchip.dat)

U25  GENOA_SP5  SOCKET6096_13568-001 IO  pkg SOCKET6096_93-4X120-45XA  page 10  (pins 337-672 of 6096)
  AD67  MFA_DATA26  BI  = M_F_CPU0_SA_DQ<26>
  AD68  VSS_AD68  POWER  = GND
  AD69  MEA_DATA25  BI  = M_E_CPU0_SA_DQ<25>
  AD70  MEA_DATA26  BI  = M_E_CPU0_SA_DQ<26>
  AD71  VSS_AD71  POWER  = GND
  AD72  MAA_DATA25  BI  = M_A_CPU0_SA_DQ<25>
  AD73  VSS_AD73  POWER  = GND
  AD74  MAA_DATA26  BI  = M_A_CPU0_SA_DQ<26>
  AE1  VSS_AE1  POWER  = GND
  AE2  MGA_DQS_H3  BI  = M_G_CPU0_SA_DQS_DP<3>
  AE3  MGA_DATA27  BI  = M_G_CPU0_SA_DQ<27>
  AE4  VSS_AE4  POWER  = GND
  AE5  MKA_DQS_H3  BI  = M_K_CPU0_SA_DQS_DP<3>
  AE6  VSS_AE6  POWER  = GND
  AE7  MKA_DATA27  BI  = M_K_CPU0_SA_DQ<27>
  AE8  VSS_AE8  POWER  = GND
  AE9  MLA_DQS_H3  BI  = M_L_CPU0_SA_DQS_DP<3>
  AE10  MLA_DATA27  BI  = M_L_CPU0_SA_DQ<27>
  AE11  VSS_AE11  POWER  = GND
  AE12  MHA_DQS_H3  BI  = M_H_CPU0_SA_DQS_DP<3>
  AE13  VSS_AE13  POWER  = GND
  AE14  MHA_DATA27  BI  = M_H_CPU0_SA_DQ<27>
  AE15  VSS_AE15  POWER  = GND
  AE16  MJA_DQS_H3  BI  = M_J_CPU0_SA_DQS_DP<3>
  AE17  MJA_DATA27  BI  = M_J_CPU0_SA_DQ<27>
  AE18  VSS_AE18  POWER  = GND
  AE19  MIA_DQS_H3  BI  = M_I_CPU0_SA_DQS_DP<3>
  AE20  VSS_AE20  POWER  = GND
  AE21  MIA_DATA27  BI  = M_I_CPU0_SA_DQ<27>
  AE22  VSS_AE22  POWER  = GND
  AE23  G2_RXN0  IN  = GMI_CPU1_G0_CPU0_G2_TX_DN<0>
  AE24  G2_RXP0  IN  = GMI_CPU1_G0_CPU0_G2_TX_DP<0>
  AE25  VSS_AE25  POWER  = GND
  AE26  G2_RXN3  IN  = GMI_CPU1_G0_CPU0_G2_TX_DN<3>
  AE27  G2_RXP3  IN  = GMI_CPU1_G0_CPU0_G2_TX_DP<3>
  AE28  VSS_AE28  POWER  = GND
  AE29  G2_RXN6  IN  = GMI_CPU1_G0_CPU0_G2_TX_DN<6>
  AE30  G2_RXP6  IN  = GMI_CPU1_G0_CPU0_G2_TX_DP<6>
  AE31  VSS_AE31  POWER  = GND
  AE32  G2_RXN9  IN  = GMI_CPU1_G0_CPU0_G2_TX_DN<9>
  AE33  G2_RXP9  IN  = GMI_CPU1_G0_CPU0_G2_TX_DP<9>
  AE34  VSS_AE34  POWER  = GND
  AE35  VSS_AE35  POWER  = GND
  AE36  VSS_AE36  POWER  = GND
  AE40  VSS_AE40  POWER  = GND
  AE41  VSS_AE41  POWER  = GND
  AE42  VSS_AE42  POWER  = GND
  AE43  G0_TXP6  OUT  = GMI_CPU0_G0_CPU1_G2_TX_DP<6>
  AE44  G0_TXN6  OUT  = GMI_CPU0_G0_CPU1_G2_TX_DN<6>
  AE45  VSS_AE45  POWER  = GND
  AE46  G0_TXP9  OUT  = GMI_CPU0_G0_CPU1_G2_TX_DP<9>
  AE47  G0_TXN9  OUT  = GMI_CPU0_G0_CPU1_G2_TX_DN<9>
  AE48  VSS_AE48  POWER  = GND
  AE49  G0_TXP12  OUT  = GMI_CPU0_G0_CPU1_G2_TX_DP<12>
  AE50  G0_TXN12  OUT  = GMI_CPU0_G0_CPU1_G2_TX_DN<12>
  AE51  VSS_AE51  POWER  = GND
  AE52  G0_TXP15  OUT  = GMI_CPU0_G0_CPU1_G2_TX_DP<15>
  AE53  G0_TXN15  OUT  = GMI_CPU0_G0_CPU1_G2_TX_DN<15>
  AE54  VSS_AE54  POWER  = GND
  AE55  MCA_DATA27  BI  = M_C_CPU0_SA_DQ<27>
  AE56  VSS_AE56  POWER  = GND
  AE57  MCA_DQS_H3  BI  = M_C_CPU0_SA_DQS_DP<3>
  AE58  VSS_AE58  POWER  = GND
  AE59  MDA_DATA27  BI  = M_D_CPU0_SA_DQ<27>
  AE60  MDA_DQS_H3  BI  = M_D_CPU0_SA_DQS_DP<3>
  AE61  VSS_AE61  POWER  = GND
  AE62  MBA_DATA27  BI  = M_B_CPU0_SA_DQ<27>
  AE63  VSS_AE63  POWER  = GND
  AE64  MBA_DQS_H3  BI  = M_B_CPU0_SA_DQS_DP<3>
  AE65  VSS_AE65  POWER  = GND
  AE66  MFA_DATA27  BI  = M_F_CPU0_SA_DQ<27>
  AE67  MFA_DQS_H3  BI  = M_F_CPU0_SA_DQS_DP<3>
  AE68  VSS_AE68  POWER  = GND
  AE69  MEA_DATA27  BI  = M_E_CPU0_SA_DQ<27>
  AE70  VSS_AE70  POWER  = GND
  AE71  MEA_DQS_H3  BI  = M_E_CPU0_SA_DQS_DP<3>
  AE72  VSS_AE72  POWER  = GND
  AE73  MAA_DATA27  BI  = M_A_CPU0_SA_DQ<27>
  AE74  MAA_DQS_H3  BI  = M_A_CPU0_SA_DQS_DP<3>
  AE75  VSS_AE75  POWER  = GND
  AF2  MGA_DQS_L3  BI  = M_G_CPU0_SA_DQS_DN<3>
  AF3  VSS_AF3  POWER  = GND
  AF4  MGA_DQS_L8  BI  = M_G_CPU0_SA_DQS_DN<8>
  AF5  VDDCR_SOC_AF5  POWER  = PVDDCR_SOC_P0
  AF6  MKA_DQS_L3  BI  = M_K_CPU0_SA_DQS_DN<3>
  AF7  MKA_DQS_L8  BI  = M_K_CPU0_SA_DQS_DN<8>
  AF8  VSS_AF8  POWER  = GND
  AF9  MLA_DQS_L3  BI  = M_L_CPU0_SA_DQS_DN<3>
  AF10  VSS_AF10  POWER  = GND
  AF11  MLA_DQS_L8  BI  = M_L_CPU0_SA_DQS_DN<8>
  AF12  VDDCR_SOC_AF12  POWER  = PVDDCR_SOC_P0
  AF13  MHA_DQS_L3  BI  = M_H_CPU0_SA_DQS_DN<3>
  AF14  MHA_DQS_L8  BI  = M_H_CPU0_SA_DQS_DN<8>
  AF15  VSS_AF15  POWER  = GND
  AF16  MJA_DQS_L3  BI  = M_J_CPU0_SA_DQS_DN<3>
  AF17  VSS_AF17  POWER  = GND
  AF18  MJA_DQS_L8  BI  = M_J_CPU0_SA_DQS_DN<8>
  AF19  VDDCR_SOC_AF19  POWER  = PVDDCR_SOC_P0
  AF20  MIA_DQS_L3  BI  = M_I_CPU0_SA_DQS_DN<3>
  AF21  MIA_DQS_L8  BI  = M_I_CPU0_SA_DQS_DN<8>
  AF22  VSS_AF22  POWER  = GND
  AF23  VDDCR_CPU0_AF23  POWER  = PVDDCR_CPU0_P0
  AF24  VDDCR_CPU0_AF24  POWER  = PVDDCR_CPU0_P0
  AF25  VSS_AF25  POWER  = GND
  AF26  VDDCR_CPU0_AF26  POWER  = PVDDCR_CPU0_P0
  AF27  VDDCR_CPU0_AF27  POWER  = PVDDCR_CPU0_P0
  AF28  VSS_AF28  POWER  = GND
  AF29  VDDCR_CPU0_AF29  POWER  = PVDDCR_CPU0_P0
  AF30  VDDCR_CPU0_AF30  POWER  = PVDDCR_CPU0_P0
  AF31  VSS_AF31  POWER  = GND
  AF32  VDDCR_CPU0_AF32  POWER  = PVDDCR_CPU0_P0
  AF33  VDDCR_CPU0_AF33  POWER  = PVDDCR_CPU0_P0
  AF34  VSS_AF34  POWER  = GND
  AF35  G2_RXN15  IN  = GMI_CPU1_G0_CPU0_G2_TX_DN<15>
  AF36  G2_RXP15  IN  = GMI_CPU1_G0_CPU0_G2_TX_DP<15>
  AF37  VSS_AF37  POWER  = GND
  AF39  VSS_AF39  POWER  = GND
  AF40  G0_TXP0  OUT  = GMI_CPU0_G0_CPU1_G2_TX_DP<0>
  AF41  G0_TXN0  OUT  = GMI_CPU0_G0_CPU1_G2_TX_DN<0>
  AF42  VSS_AF42  POWER  = GND
  AF43  VDDCR_CPU0_AF43  POWER  = PVDDCR_CPU0_P0
  AF44  VDDCR_CPU0_AF44  POWER  = PVDDCR_CPU0_P0
  AF45  VSS_AF45  POWER  = GND
  AF46  VDDCR_CPU0_AF46  POWER  = PVDDCR_CPU0_P0
  AF47  VDDCR_CPU0_AF47  POWER  = PVDDCR_CPU0_P0
  AF48  VSS_AF48  POWER  = GND
  AF49  VDDCR_CPU0_AF49  POWER  = PVDDCR_CPU0_P0
  AF50  VDDCR_CPU0_AF50  POWER  = PVDDCR_CPU0_P0
  AF51  VSS_AF51  POWER  = GND
  AF52  VDDCR_CPU0_AF52  POWER  = PVDDCR_CPU0_P0
  AF53  VDDCR_CPU0_AF53  POWER  = PVDDCR_CPU0_P0
  AF54  VSS_AF54  POWER  = GND
  AF55  MCA_DQS_L8  BI  = M_C_CPU0_SA_DQS_DN<8>
  AF56  MCA_DQS_L3  BI  = M_C_CPU0_SA_DQS_DN<3>
  AF57  VDDIO_AF57  POWER  = PVDDIO_P0
  AF58  MDA_DQS_L8  BI  = M_D_CPU0_SA_DQS_DN<8>
  AF59  VSS_AF59  POWER  = GND
  AF60  MDA_DQS_L3  BI  = M_D_CPU0_SA_DQS_DN<3>
  AF61  VSS_AF61  POWER  = GND
  AF62  MBA_DQS_L8  BI  = M_B_CPU0_SA_DQS_DN<8>
  AF63  MBA_DQS_L3  BI  = M_B_CPU0_SA_DQS_DN<3>
  AF64  VDDIO_AF64  POWER  = PVDDIO_P0
  AF65  MFA_DQS_L8  BI  = M_F_CPU0_SA_DQS_DN<8>
  AF66  VSS_AF66  POWER  = GND
  AF67  MFA_DQS_L3  BI  = M_F_CPU0_SA_DQS_DN<3>
  AF68  VSS_AF68  POWER  = GND
  AF69  MEA_DQS_L8  BI  = M_E_CPU0_SA_DQS_DN<8>
  AF70  MEA_DQS_L3  BI  = M_E_CPU0_SA_DQS_DN<3>
  AF71  VDDIO_AF71  POWER  = PVDDIO_P0
  AF72  MAA_DQS_L8  BI  = M_A_CPU0_SA_DQS_DN<8>
  AF73  VSS_AF73  POWER  = GND
  AF74  MAA_DQS_L3  BI  = M_A_CPU0_SA_DQS_DN<3>
  AG1  VSS_AG1  POWER  = GND
  AG2  MGA_DATA28  BI  = M_G_CPU0_SA_DQ<28>
  AG3  MGA_DQS_H8  BI  = M_G_CPU0_SA_DQS_DP<8>
  AG4  VSS_AG4  POWER  = GND
  AG5  MKA_DATA28  BI  = M_K_CPU0_SA_DQ<28>
  AG6  VSS_AG6  POWER  = GND
  AG7  MKA_DQS_H8  BI  = M_K_CPU0_SA_DQS_DP<8>
  AG8  VSS_AG8  POWER  = GND
  AG9  MLA_DATA28  BI  = M_L_CPU0_SA_DQ<28>
  AG10  MLA_DQS_H8  BI  = M_L_CPU0_SA_DQS_DP<8>
  AG11  VSS_AG11  POWER  = GND
  AG12  MHA_DATA28  BI  = M_H_CPU0_SA_DQ<28>
  AG13  VSS_AG13  POWER  = GND
  AG14  MHA_DQS_H8  BI  = M_H_CPU0_SA_DQS_DP<8>
  AG15  VSS_AG15  POWER  = GND
  AG16  MJA_DATA28  BI  = M_J_CPU0_SA_DQ<28>
  AG17  MJA_DQS_H8  BI  = M_J_CPU0_SA_DQS_DP<8>
  AG18  VSS_AG18  POWER  = GND
  AG19  MIA_DATA28  BI  = M_I_CPU0_SA_DQ<28>
  AG20  VSS_AG20  POWER  = GND
  AG21  MIA_DQS_H8  BI  = M_I_CPU0_SA_DQS_DP<8>
  AG22  VSS_AG22  POWER  = GND
  AG23  G2_RXN2  IN  = GMI_CPU1_G0_CPU0_G2_TX_DN<2>
  AG24  G2_RXP2  IN  = GMI_CPU1_G0_CPU0_G2_TX_DP<2>
  AG25  VSS_AG25  POWER  = GND
  AG26  G2_RXN5  IN  = GMI_CPU1_G0_CPU0_G2_TX_DN<5>
  AG27  G2_RXP5  IN  = GMI_CPU1_G0_CPU0_G2_TX_DP<5>
  AG28  VSS_AG28  POWER  = GND
  AG29  G2_RXN8  IN  = GMI_CPU1_G0_CPU0_G2_TX_DN<8>
  AG30  G2_RXP8  IN  = GMI_CPU1_G0_CPU0_G2_TX_DP<8>
  AG31  VSS_AG31  POWER  = GND
  AG32  G2_RXN12  IN  = GMI_CPU1_G0_CPU0_G2_TX_DN<12>
  AG33  G2_RXP12  IN  = GMI_CPU1_G0_CPU0_G2_TX_DP<12>
  AG34  VSS_AG34  POWER  = GND
  AG35  VDDCR_CPU0_AG35  POWER  = PVDDCR_CPU0_P0
  AG36  VDDCR_CPU0_AG36  POWER  = PVDDCR_CPU0_P0
  AG40  VDDCR_CPU0_AG40  POWER  = PVDDCR_CPU0_P0
  AG41  VDDCR_CPU0_AG41  POWER  = PVDDCR_CPU0_P0
  AG42  VSS_AG42  POWER  = GND
  AG43  G0_TXP3  OUT  = GMI_CPU0_G0_CPU1_G2_TX_DP<3>
  AG44  G0_TXN3  OUT  = GMI_CPU0_G0_CPU1_G2_TX_DN<3>
  AG45  VSS_AG45  POWER  = GND
  AG46  G0_TXP7  OUT  = GMI_CPU0_G0_CPU1_G2_TX_DP<7>
  AG47  G0_TXN7  OUT  = GMI_CPU0_G0_CPU1_G2_TX_DN<7>
  AG48  VSS_AG48  POWER  = GND
  AG49  G0_TXP10  OUT  = GMI_CPU0_G0_CPU1_G2_TX_DP<10>
  AG50  G0_TXN10  OUT  = GMI_CPU0_G0_CPU1_G2_TX_DN<10>
  AG51  VSS_AG51  POWER  = GND
  AG52  G0_TXP13  OUT  = GMI_CPU0_G0_CPU1_G2_TX_DP<13>
  AG53  G0_TXN13  OUT  = GMI_CPU0_G0_CPU1_G2_TX_DN<13>
  AG54  VSS_AG54  POWER  = GND
  AG55  MCA_DQS_H8  BI  = M_C_CPU0_SA_DQS_DP<8>
  AG56  VSS_AG56  POWER  = GND
  AG57  MCA_DATA28  BI  = M_C_CPU0_SA_DQ<28>
  AG58  VSS_AG58  POWER  = GND
  AG59  MDA_DQS_H8  BI  = M_D_CPU0_SA_DQS_DP<8>
  AG60  MDA_DATA28  BI  = M_D_CPU0_SA_DQ<28>
  AG61  VSS_AG61  POWER  = GND
  AG62  MBA_DQS_H8  BI  = M_B_CPU0_SA_DQS_DP<8>
  AG63  VSS_AG63  POWER  = GND
  AG64  MBA_DATA28  BI  = M_B_CPU0_SA_DQ<28>
  AG65  VSS_AG65  POWER  = GND
  AG66  MFA_DQS_H8  BI  = M_F_CPU0_SA_DQS_DP<8>
  AG67  MFA_DATA28  BI  = M_F_CPU0_SA_DQ<28>
  AG68  VSS_AG68  POWER  = GND
  AG69  MEA_DQS_H8  BI  = M_E_CPU0_SA_DQS_DP<8>
  AG70  VSS_AG70  POWER  = GND
  AG71  MEA_DATA28  BI  = M_E_CPU0_SA_DQ<28>
  AG72  VSS_AG72  POWER  = GND
  AG73  MAA_DQS_H8  BI  = M_A_CPU0_SA_DQS_DP<8>
  AG74  MAA_DATA28  BI  = M_A_CPU0_SA_DQ<28>
  AG75  VSS_AG75  POWER  = GND
  AH2  MGA_DATA30  BI  = M_G_CPU0_SA_DQ<30>
  AH3  VSS_AH3  POWER  = GND
  AH4  MGA_DATA29  BI  = M_G_CPU0_SA_DQ<29>
  AH5  VSS_AH5  POWER  = GND
  AH6  MKA_DATA30  BI  = M_K_CPU0_SA_DQ<30>
  AH7  MKA_DATA29  BI  = M_K_CPU0_SA_DQ<29>
  AH8  VSS_AH8  POWER  = GND
  AH9  MLA_DATA30  BI  = M_L_CPU0_SA_DQ<30>
  AH10  VSS_AH10  POWER  = GND
  AH11  MLA_DATA29  BI  = M_L_CPU0_SA_DQ<29>
  AH12  VSS_AH12  POWER  = GND
  AH13  MHA_DATA30  BI  = M_H_CPU0_SA_DQ<30>
  AH14  MHA_DATA29  BI  = M_H_CPU0_SA_DQ<29>
  AH15  VSS_AH15  POWER  = GND
  AH16  MJA_DATA30  BI  = M_J_CPU0_SA_DQ<30>
  AH17  VSS_AH17  POWER  = GND
  AH18  MJA_DATA29  BI  = M_J_CPU0_SA_DQ<29>
  AH19  VSS_AH19  POWER  = GND
  AH20  MIA_DATA30  BI  = M_I_CPU0_SA_DQ<30>
  AH21  MIA_DATA29  BI  = M_I_CPU0_SA_DQ<29>
  AH22  VDDCR_SOC_AH22  POWER  = PVDDCR_SOC_P0
  AH23  VSS_AH23  POWER  = GND
  AH24  VSS_AH24  POWER  = GND
  AH25  VSS_AH25  POWER  = GND
  AH26  VSS_AH26  POWER  = GND
  AH27  VSS_AH27  POWER  = GND
  AH28  VSS_AH28  POWER  = GND
  AH29  VSS_AH29  POWER  = GND
  AH30  VSS_AH30  POWER  = GND
  AH31  VSS_AH31  POWER  = GND
  AH32  VSS_AH32  POWER  = GND
  AH33  VSS_AH33  POWER  = GND
  AH34  VSS_AH34  POWER  = GND
  AH35  \g3_rxn13||sata35_rxn\  IN  = P5E_CPU0_G3_RX_DN<13>
  AH36  \g3_rxp13||sata35_rxp\  IN  = P5E_CPU0_G3_RX_DP<13>
  AH37  VSS_AH37  POWER  = GND
  AH39  VSS_AH39  POWER  = GND
  AH40  G1_TXP2  OUT  = GMI_CPU0_G1_CPU1_G3_TX_DP<2>
  AH41  G1_TXN2  OUT  = GMI_CPU0_G1_CPU1_G3_TX_DN<2>
  AH42  VSS_AH42  POWER  = GND
  AH43  VSS_AH43  POWER  = GND
  AH44  VSS_AH44  POWER  = GND
  AH45  VSS_AH45  POWER  = GND
  AH46  VSS_AH46  POWER  = GND
  AH47  VSS_AH47  POWER  = GND
  AH48  VSS_AH48  POWER  = GND
  AH49  VSS_AH49  POWER  = GND
  AH50  VSS_AH50  POWER  = GND
  AH51  VSS_AH51  POWER  = GND
  AH52  VSS_AH52  POWER  = GND
  AH53  VSS_AH53  POWER  = GND
  AH54  VDDIO_AH54  POWER  = PVDDIO_P0
  AH55  MCA_DATA29  BI  = M_C_CPU0_SA_DQ<29>
  AH56  MCA_DATA30  BI  = M_C_CPU0_SA_DQ<30>
  AH57  VSS_AH57  POWER  = GND
  AH58  MDA_DATA29  BI  = M_D_CPU0_SA_DQ<29>
  AH59  VSS_AH59  POWER  = GND
  AH60  MDA_DATA30  BI  = M_D_CPU0_SA_DQ<30>
  AH61  VSS_AH61  POWER  = GND
  AH62  MBA_DATA29  BI  = M_B_CPU0_SA_DQ<29>
  AH63  MBA_DATA30  BI  = M_B_CPU0_SA_DQ<30>
  AH64  VSS_AH64  POWER  = GND
  AH65  MFA_DATA29  BI  = M_F_CPU0_SA_DQ<29>
  AH66  VSS_AH66  POWER  = GND
  AH67  MFA_DATA30  BI  = M_F_CPU0_SA_DQ<30>
  AH68  VSS_AH68  POWER  = GND
  AH69  MEA_DATA29  BI  = M_E_CPU0_SA_DQ<29>
  AH70  MEA_DATA30  BI  = M_E_CPU0_SA_DQ<30>
  AH71  VSS_AH71  POWER  = GND
  AH72  MAA_DATA29  BI  = M_A_CPU0_SA_DQ<29>
  AH73  VSS_AH73  POWER  = GND
  AH74  MAA_DATA30  BI  = M_A_CPU0_SA_DQ<30>
  AJ1  VSS_AJ1  POWER  = GND
  AJ2  MGA_CHECK0  BI  = M_G_CPU0_SA_CB<0>
  AJ3  MGA_DATA31  BI  = M_G_CPU0_SA_DQ<31>
  AJ4  VDDCR_SOC_AJ4  POWER  = PVDDCR_SOC_P0
  AJ5  MKA_CHECK0  BI  = M_K_CPU0_SA_CB<0>
  AJ6  VSS_AJ6  POWER  = GND
  AJ7  MKA_DATA31  BI  = M_K_CPU0_SA_DQ<31>
  AJ8  VSS_AJ8  POWER  = GND
  AJ9  MLA_CHECK0  BI  = M_L_CPU0_SA_CB<0>
  AJ10  MLA_DATA31  BI  = M_L_CPU0_SA_DQ<31>
  AJ11  VDDCR_SOC_AJ11  POWER  = PVDDCR_SOC_P0
  AJ12  MHA_CHECK0  BI  = M_H_CPU0_SA_CB<0>
  AJ13  VSS_AJ13  POWER  = GND
  AJ14  MHA_DATA31  BI  = M_H_CPU0_SA_DQ<31>
  AJ15  VSS_AJ15  POWER  = GND
  AJ16  MJA_CHECK0  BI  = M_J_CPU0_SA_CB<0>
  AJ17  MJA_DATA31  BI  = M_J_CPU0_SA_DQ<31>
  AJ18  VDDCR_SOC_AJ18  POWER  = PVDDCR_SOC_P0
  AJ19  MIA_CHECK0  BI  = M_I_CPU0_SA_CB<0>
  AJ20  VSS_AJ20  POWER  = GND
  AJ21  MIA_DATA31  BI  = M_I_CPU0_SA_DQ<31>
  AJ22  VSS_AJ22  POWER  = GND
  AJ23  \g3_rxn1||sata21_rxn\  IN  = P5E_CPU0_G3_RX_DN<1>
  AJ24  \g3_rxp1||sata21_rxp\  IN  = P5E_CPU0_G3_RX_DP<1>
  AJ25  VSS_AJ25  POWER  = GND
  AJ26  \g3_rxn4||sata24_rxn\  IN  = P5E_CPU0_G3_RX_DN<4>
  AJ27  \g3_rxp4||sata24_rxp\  IN  = P5E_CPU0_G3_RX_DP<4>
  AJ28  VSS_AJ28  POWER  = GND
  AJ29  \g3_rxn7||sata27_rxn\  IN  = P5E_CPU0_G3_RX_DN<7>
  AJ30  \g3_rxp7||sata27_rxp\  IN  = P5E_CPU0_G3_RX_DP<7>
  AJ31  VSS_AJ31  POWER  = GND
  AJ32  \g3_rxn10||sata32_rxn\  IN  = P5E_CPU0_G3_RX_DN<10>
  AJ33  \g3_rxp10||sata32_rxp\  IN  = P5E_CPU0_G3_RX_DP<10>
  AJ34  VSS_AJ34  POWER  = GND
  AJ35  VSS_AJ35  POWER  = GND
  AJ36  VSS_AJ36  POWER  = GND
  AJ40  VSS_AJ40  POWER  = GND
  AJ41  VSS_AJ41  POWER  = GND
  AJ42  VSS_AJ42  POWER  = GND
  AJ43  G1_TXP5  OUT  = GMI_CPU0_G1_CPU1_G3_TX_DP<5>
